FILE_TYPE = MACRO_DRAWING;
SET COLOR_WIRE YELLOW;
SET COLOR_PROP ORANGE;
SET COLOR_DOT WHITE;
SET COLOR_ARC YELLOW;
SET COLOR_BODY GREEN;
SET COLOR_NOTE PURPLE;
SET PROP_DISPLAY VALUE;
SET PAGE_NUMBER P113;
FORCEADD QUANTA_TITLE_BLOCK_C..1
(0 0);
FORCEPROP 1 LAST CUSTOM_TXT_CDS <NAME_2>
J 0
(-3175 50);
FORCEPROP 1 LAST CUSTOM_TXT_CDS <NAME_1>
J 0
(-3175 175);
FORCEPROP 1 LAST CUSTOM_TXT_CDS <Q_NUMBER>
J 0
(-1403 103);
DISPLAY 1.212766 (-1403 103);
FORCEPROP 1 LAST CUSTOM_TXT_CDS <Q_PROJ>
J 0
(-2382 102);
DISPLAY 1.212766 (-2382 102);
FORCEPROP 1 LAST CUSTOM_TXT_CDS <Q_REV>
J 0
(-184 103);
DISPLAY 1.212766 (-184 103);
FORCEPROP 1 LAST CUSTOM_TXT_CDS <CON_LAST_MODIFIED>
J 0
(-1885 15);
DISPLAY 0.978723 (-1885 15);
FORCEPROP 1 LAST CUSTOM_TXT_CDS <CON_PAGE_NUM> OF <CON_TOTAL_PAGES>
J 0
(-446 18);
DISPLAY 0.978723 (-446 18);
FORCEPROP 1 LAST Q_TITLE Blank
J 0
(-9300 50);
DISPLAY 2.446809 (-9300 50);
PAINT GREEN (-9300 50);
FORCEPROP 2 LAST PAGE_BORDER TRUE
J 0
(-7890 5250);
DISPLAY 0.638298 (-7890 5250);
PAINT PINK (-7890 5250);
DISPLAY INVISIBLE (-7890 5250);
FORCEPROP 1 LAST CDS_LMAN_SYM_OUTLINE -9475,6775,100,-125
J 0
(0 0);
DISPLAY 0.468085 (0 0);
PAINT GREEN (0 0);
DISPLAY INVISIBLE (0 0);
FORCEPROP 2 LAST CDS_LIB pure_quanta
J 0
(0 0);
DISPLAY INVISIBLE (0 0);
FORCEPROP 2 LAST CDS_XR_PAGE_TITLE CR-114 : @T6G_MB_LIB.T6G(SCH_1):PAGE114
J 0
(-7890 5250);
DISPLAY 0.638298 (-7890 5250);
PAINT PINK (-7890 5250);
DISPLAY INVISIBLE (-7890 5250);
FORCEPROP 2 LAST CUSTOM_TXT_CDS <XR_PAGE_TITLE>
J 0
(-7890 5250);
DISPLAY 0.638298 (-7890 5250);
PAINT PINK (-7890 5250);
DISPLAY INVISIBLE (-7890 5250);
FORCEPROP 1 LAST COMMENT_BODY TRUE
J 0
(12 -13);
DISPLAY 0.978723 (12 -13);
PAINT GREEN (12 -13);
DISPLAY INVISIBLE (12 -13);
FORCEPROP 1 LAST Q_DEPT BU9
J 1
(-3763 49);
DISPLAY 1.957447 (-3763 49);
PAINT GREEN (-3763 49);
DISPLAY INVISIBLE (-3763 49);
FORCEPROP 0 LAST CDS_CON_LAST_MODIFIED Thu Aug 24 10:14:19 2023
J 0
(-1885 15);
DISPLAY INVISIBLE (-1885 15);
QUIT
